# T6G (Grand Teton) — schematic parts with pin connectivity, parts 8230–8230 of 8303; source: Cadence DE-HDL packaged netlist (pstxprt.dat, pstxnet.dat, pstchip.dat)

U6013  PT5161LRS  IC  pkg BGA354_8-9X22-8  page 307
  A1  NCF_GND1  POWER  = NCF_A1_CPU0_P3_GND
  A35  NCF_GND2  POWER  = NCF_CPU0_P3_GND
  AA10  B_PETN1  OUT  = P5E_CPU0_P3_TX_BUF_DN<14>
  AA29  A_PETN1  OUT  = P5E_CPU0_P3_RX_DN<14>
  AB1  A_PERP1  IN  = P5E_CPU0_P3_RX_BUF_DP<14>
  AB35  B_PERN1  IN  = P5E_CPU0_P3_TX_C_DN<14>
  AC4  GND4  POWER  = GND
  AC13  GND1  POWER  = GND
  AC17  PWR_2A_1  POWER  = P0V9_CPU0_RT3_2A
  AC20  PWR_2A_2  POWER  = P0V9_CPU0_RT3_2A
  AC22  GND2  POWER  = GND
  AC32  GND3  POWER  = GND
  AD2  GND5  POWER  = GND
  AD34  GND6  POWER  = GND
  AE1  GND7  POWER  = GND
  AE35  GND8  POWER  = GND
  AF7  B_PETP2  OUT  = P5E_CPU0_P3_TX_BUF_DP<13>
  AF26  A_PETP2  OUT  = P5E_CPU0_P3_RX_DP<13>
  AG2  A_PERN2  IN  = P5E_CPU0_P3_RX_BUF_DN<13>
  AG34  B_PERP2  IN  = P5E_CPU0_P3_TX_C_DN<13>
  AH10  B_PETN2  OUT  = P5E_CPU0_P3_TX_BUF_DN<13>
  AH29  A_PETN2  OUT  = P5E_CPU0_P3_RX_DN<13>
  AJ1  A_PERP2  IN  = P5E_CPU0_P3_RX_BUF_DP<13>
  AJ35  B_PERN2  IN  = P5E_CPU0_P3_TX_C_DP<13>
  AK4  GND12  POWER  = GND
  AK13  GND9  POWER  = GND
  AK17  PWR_2A_3  POWER  = P0V9_CPU0_RT3_2A
  AK20  PWR_2A_4  POWER  = P0V9_CPU0_RT3_2A
  AK22  GND10  POWER  = GND
  AK32  GND11  POWER  = GND
  AL2  GND13  POWER  = GND
  AL34  GND14  POWER  = GND
  AM1  GND15  POWER  = GND
  AM35  GND16  POWER  = GND
  AN7  B_PETP3  OUT  = P5E_CPU0_P3_TX_BUF_DP<12>
  AN26  A_PETP3  OUT  = P5E_CPU0_P3_RX_DP<12>
  AP2  A_PERN3  IN  = P5E_CPU0_P3_RX_BUF_DN<12>
  AP34  B_PERP3  IN  = P5E_CPU0_P3_TX_C_DN<12>
  AR10  B_PETN3  OUT  = P5E_CPU0_P3_TX_BUF_DN<12>
  AR29  A_PETN3  OUT  = P5E_CPU0_P3_RX_DN<12>
  AT1  A_PERP3  IN  = P5E_CPU0_P3_RX_BUF_DP<12>
  AT35  B_PERN3  IN  = P5E_CPU0_P3_TX_C_DP<12>
  AU4  GND20  POWER  = GND
  AU13  GND17  POWER  = GND
  AU17  PWR_2A_5  POWER  = P0V9_CPU0_RT3_2A
  AU20  PWR_2A_6  POWER  = P0V9_CPU0_RT3_2A
  AU22  GND18  POWER  = GND
  AU32  GND19  POWER  = GND
  AV2  GND21  POWER  = GND
  AV34  GND22  POWER  = GND
  AW1  GND23  POWER  = GND
  AW35  GND24  POWER  = GND
  AY7  B_PETP4  OUT  = P5E_CPU0_P3_TX_BUF_DP<11>
  AY26  A_PETP4  OUT  = P5E_CPU0_P3_RX_DP<11>
  B3  JTAG_TCK  IN  = JTAG_TCK_RT_CPU0_P3
  B6  JTAG_TDI  IN  = JTAG_TDI_RT_CPU0_P3
  B9  JTAG_TDO  OUT  = JTAG_TDO_RT_CPU0_P3
  B12  JTAG_TMS  IN  = JTAG_TMS_RT_CPU0_P3
  B16  REFCLK_OUTP  OUT  = NC
  B19  GND25  POWER  = GND
  B23  SMB_ADDR2  IN  = RT_CPU0_P3_ADDR2
  B25  SMB_ADDR3  IN  = RT_CPU0_P3_ADDR3
  B28  SMBDAT  BI  = SMB_RT_CPU0_P3_R2_SDA
  B31  SMBCLK  BI  = SMB_RT_CPU0_P3_R2_SCL
  BA2  A_PERN4  IN  = P5E_CPU0_P3_RX_BUF_DN<11>
  BA34  B_PERP4  IN  = P5E_CPU0_P3_TX_C_DN<11>
  BB10  B_PETN4  OUT  = P5E_CPU0_P3_TX_BUF_DN<11>
  BB29  A_PETN4  OUT  = P5E_CPU0_P3_RX_DN<11>
  BC1  A_PERP4  IN  = P5E_CPU0_P3_RX_BUF_DP<11>
  BC35  B_PERN4  IN  = P5E_CPU0_P3_TX_C_DP<11>
  BD4  GND29  POWER  = GND
  BD13  GND26  POWER  = GND
  BD17  PWR_2A_7  POWER  = P0V9_CPU0_RT3_2A_2D
  BD20  PWR_2A_8  POWER  = P0V9_CPU0_RT3_2A_2D
  BD22  GND27  POWER  = GND
  BD32  GND28  POWER  = GND
  BE2  GND30  POWER  = GND
  BE34  GND31  POWER  = GND
  BF1  GND32  POWER  = GND
  BF35  GND33  POWER  = GND
  BG7  B_PETP5  OUT  = P5E_CPU0_P3_TX_BUF_DP<10>
  BG26  A_PETP5  OUT  = P5E_CPU0_P3_RX_DP<10>
  BH2  A_PERN5  IN  = P5E_CPU0_P3_RX_BUF_DN<10>
  BH34  B_PERP5  IN  = P5E_CPU0_P3_TX_C_DN<10>
  BJ10  B_PETN5  OUT  = P5E_CPU0_P3_TX_BUF_DN<10>
  BJ29  A_PETN5  OUT  = P5E_CPU0_P3_RX_DN<10>
  BK1  A_PERP5  IN  = P5E_CPU0_P3_RX_BUF_DP<10>
  BK35  B_PERN5  IN  = P5E_CPU0_P3_TX_C_DP<10>
  BL4  GND37  POWER  = GND
  BL13  GND34  POWER  = GND
  BL17  PWR_2D_1  POWER  = P0V9_CPU0_RT_2D
  BL20  PWR_2D_2  POWER  = P0V9_CPU0_RT_2D
  BL22  GND35  POWER  = GND
  BL32  GND36  POWER  = GND
  BM2  GND38  POWER  = GND
  BM34  GND39  POWER  = GND
  BN1  GND40  POWER  = GND
  BN35  GND41  POWER  = GND
  BP7  B_PETP6  OUT  = P5E_CPU0_P3_TX_BUF_DP<9>
  BP26  A_PETP6  OUT  = P5E_CPU0_P3_RX_DP<9>
  BR2  A_PERN6  IN  = P5E_CPU0_P3_RX_BUF_DN<9>
  BR34  B_PERP6  IN  = P5E_CPU0_P3_TX_C_DN<9>
  BT10  B_PETN6  OUT  = P5E_CPU0_P3_TX_BUF_DN<9>
  BT29  A_PETN6  OUT  = P5E_CPU0_P3_RX_DN<9>
  BU1  A_PERP6  IN  = P5E_CPU0_P3_RX_BUF_DP<9>
  BU35  B_PERN6  IN  = P5E_CPU0_P3_TX_C_DP<9>
  BV4  GND45  POWER  = GND
  BV13  GND42  POWER  = GND
  BV17  PWR_1D  POWER  = P1V8_CPU0_RT3_1A_1D
  BV20  PWR_1A_1  POWER  = P1V8_CPU0_RT3_1A
  BV22  GND43  POWER  = GND
  BV32  GND44  POWER  = GND
  BW2  GND46  POWER  = GND
  BW34  GND47  POWER  = GND
  BY1  GND48  POWER  = GND
  BY35  GND49  POWER  = GND
  C2  NCF_GND3  POWER  = NCF_CPU0_P3_GND
  C34  NCF_GND4  POWER  = NCF_CPU0_P3_GND
  CA7  B_PETP7  OUT  = P5E_CPU0_P3_TX_BUF_DP<8>
  CA26  A_PETP7  OUT  = P5E_CPU0_P3_RX_DP<8>
  CB2  A_PERN7  IN  = P5E_CPU0_P3_RX_BUF_DN<8>
  CB34  B_PERP7  IN  = P5E_CPU0_P3_TX_C_DN<8>
  CC10  B_PETN7  OUT  = P5E_CPU0_P3_TX_BUF_DN<8>
  CC29  A_PETN7  OUT  = P5E_CPU0_P3_RX_DN<8>
  CD1  A_PERP7  IN  = P5E_CPU0_P3_RX_BUF_DP<8>
  CD35  B_PERN7  IN  = P5E_CPU0_P3_TX_C_DP<8>
  CE4  GND53  POWER  = GND
  CE13  GND50  POWER  = GND
  CE17  PWR_1A_2  POWER  = P1V8_CPU0_RT3_1A
  CE20  PWR_1A_3  POWER  = P1V8_CPU0_RT3_1A
  CE22  GND51  POWER  = GND
  CE32  GND52  POWER  = GND
  CF2  GND54  POWER  = GND
  CF34  GND55  POWER  = GND
  CG1  GND56  POWER  = GND
  CG35  GND57  POWER  = GND
  CH7  B_PETP8  OUT  = P5E_CPU0_P3_TX_BUF_DP<7>
  CH26  A_PETP8  OUT  = P5E_CPU0_P3_RX_DP<7>
  CJ2  A_PERN8  IN  = P5E_CPU0_P3_RX_BUF_DN<7>
  CJ34  B_PERP8  IN  = P5E_CPU0_P3_TX_C_DN<7>
  CK10  B_PETN8  OUT  = P5E_CPU0_P3_TX_BUF_DN<7>
  CK29  A_PETN8  OUT  = P5E_CPU0_P3_RX_DN<7>
  CL1  A_PERP8  IN  = P5E_CPU0_P3_RX_BUF_DP<7>
  CL35  B_PERN8  IN  = P5E_CPU0_P3_TX_C_DP<7>
  CM4  GND61  POWER  = GND
  CM13  GND58  POWER  = GND
  CM17  PWR_1A_4  POWER  = P1V8_CPU0_RT3_1A
  CM20  PWR_1A_5  POWER  = P1V8_CPU0_RT3_1A
  CM22  GND59  POWER  = GND
  CM32  GND60  POWER  = GND
  CN2  GND62  POWER  = GND
  CN34  GND63  POWER  = GND
  CP1  GND64  POWER  = GND
  CP35  GND65  POWER  = GND
  CR7  B_PETP9  OUT  = P5E_CPU0_P3_TX_BUF_DP<6>
  CR26  A_PETP9  OUT  = P5E_CPU0_P3_RX_DP<6>
  CT2  A_PERN9  IN  = P5E_CPU0_P3_RX_BUF_DN<6>
  CT34  B_PERP9  IN  = P5E_CPU0_P3_TX_C_DN<6>
  CU10  B_PETN9  OUT  = P5E_CPU0_P3_TX_BUF_DN<6>
  CU29  A_PETN9  OUT  = P5E_CPU0_P3_RX_DN<6>
  CV1  A_PERP9  IN  = P5E_CPU0_P3_RX_BUF_DP<6>
  CV35  B_PERN9  IN  = P5E_CPU0_P3_TX_C_DP<6>
  CW4  GND69  POWER  = GND
  CW13  GND66  POWER  = GND
  CW17  PWR_2D_3  POWER  = P0V9_CPU0_RT_2D
  CW20  PWR_2D_4  POWER  = P0V9_CPU0_RT_2D
  CW22  GND67  POWER  = GND
  CW32  GND68  POWER  = GND
  CY2  GND70  POWER  = GND
  CY34  GND71  POWER  = GND
  D1  NCF_GND5  POWER  = NCF_CPU0_P3_GND
  D35  NCF_GND6  POWER  = NCF_CPU0_P3_GND
  DA1  GND72  POWER  = GND
  DA35  GND73  POWER  = GND
  DB7  B_PETP10  OUT  = P5E_CPU0_P3_TX_BUF_DP<5>
  DB26  A_PETP10  OUT  = P5E_CPU0_P3_RX_DP<5>
  DC2  A_PERN10  IN  = P5E_CPU0_P3_RX_BUF_DN<5>
  DC34  B_PERP10  IN  = P5E_CPU0_P3_TX_C_DN<5>
  DD10  B_PETN10  OUT  = P5E_CPU0_P3_TX_BUF_DN<5>
  DD29  A_PETN10  OUT  = P5E_CPU0_P3_RX_DN<5>
  DE1  A_PERP10  IN  = P5E_CPU0_P3_RX_BUF_DP<5>
  DE35  B_PERN10  IN  = P5E_CPU0_P3_TX_C_DP<5>
  DF4  GND77  POWER  = GND
  DF13  GND74  POWER  = GND
  DF17  PWR_2A_9  POWER  = P0V9_CPU0_RT3_2A_2D
  DF20  PWR_2A_10  POWER  = P0V9_CPU0_RT3_2A_2D
  DF22  GND75  POWER  = GND
  DF32  GND76  POWER  = GND
  DG2  GND78  POWER  = GND
  DG34  GND79  POWER  = GND
  DH1  GND80  POWER  = GND
  DH35  GND81  POWER  = GND
  DJ7  B_PETP11  OUT  = P5E_CPU0_P3_TX_BUF_DP<4>
  DJ26  A_PETP11  OUT  = P5E_CPU0_P3_RX_DP<4>
  DK2  A_PERN11  IN  = P5E_CPU0_P3_RX_BUF_DN<4>
  DK34  B_PERP11  IN  = P5E_CPU0_P3_TX_C_DN<4>
  DL10  B_PETN11  OUT  = P5E_CPU0_P3_TX_BUF_DN<4>
  DL29  A_PETN11  OUT  = P5E_CPU0_P3_RX_DN<4>
  DM1  A_PERP11  IN  = P5E_CPU0_P3_RX_BUF_DP<4>
  DM35  B_PERN11  IN  = P5E_CPU0_P3_TX_C_DP<4>
  DN4  GND85  POWER  = GND
  DN13  GND82  POWER  = GND
  DN17  PWR_2A_11  POWER  = P0V9_CPU0_RT3_2A
  DN20  PWR_2A_12  POWER  = P0V9_CPU0_RT3_2A
  DN22  GND83  POWER  = GND
  DN32  GND84  POWER  = GND
  DP2  GND86  POWER  = GND
  DP34  GND87  POWER  = GND
  DR1  GND88  POWER  = GND
  DR35  GND89  POWER  = GND
  DT7  B_PETP12  OUT  = P5E_CPU0_P3_TX_BUF_DP<3>
  DT26  A_PETP12  OUT  = P5E_CPU0_P3_RX_DP<3>
  DU2  A_PERN12  IN  = P5E_CPU0_P3_RX_BUF_DN<3>
  DU34  B_PERP12  IN  = P5E_CPU0_P3_TX_C_DN<3>
  DV10  B_PETN12  OUT  = P5E_CPU0_P3_TX_BUF_DN<3>
  DV29  A_PETN12  OUT  = P5E_CPU0_P3_RX_DN<3>
  DW1  A_PERP12  IN  = P5E_CPU0_P3_RX_BUF_DP<3>
  DW35  B_PERN12  IN  = P5E_CPU0_P3_TX_C_DP<3>
  DY4  GND93  POWER  = GND
  DY13  GND90  POWER  = GND
  DY17  PWR_2A_13  POWER  = P0V9_CPU0_RT3_2A
  DY20  PWR_2A_14  POWER  = P0V9_CPU0_RT3_2A
  DY22  GND91  POWER  = GND
  DY32  GND92  POWER  = GND
  E8  JTAG_TRST_N  IN  = JTAG_TRST_RT_CPU0_P3_N
  E11  RXDET_BYP  IN  = RXDET_BYP_RT_CPU0_P3
  E14  GND94  POWER  = GND
  E18  REFCLK_OUTN  OUT  = NC
  E27  GND95  POWER  = GND
  E30  T_SENSE  OUT  = GND
  E33  GND96  POWER  = GND
  EA2  GND97  POWER  = GND
  EA34  GND98  POWER  = GND
  EB1  GND99  POWER  = GND
  EB35  GND100  POWER  = GND
  EC7  B_PETP13  OUT  = P5E_CPU0_P3_TX_BUF_DP<2>
  EC26  A_PETP13  OUT  = P5E_CPU0_P3_RX_DP<2>
  ED2  A_PERN13  IN  = P5E_CPU0_P3_RX_BUF_DN<2>
  ED34  B_PERP13  IN  = P5E_CPU0_P3_TX_C_DN<2>
  EE10  B_PETN13  OUT  = P5E_CPU0_P3_TX_BUF_DN<2>
  EE29  A_PETN13  OUT  = P5E_CPU0_P3_RX_DN<2>
  EF1  A_PERP13  IN  = P5E_CPU0_P3_RX_BUF_DP<2>
  EF35  B_PERN13  IN  = P5E_CPU0_P3_TX_C_DP<2>
  EG4  GND104  POWER  = GND
  EG13  GND101  POWER  = GND
  EG17  PWR_2A_15  POWER  = P0V9_CPU0_RT3_2A
  EG20  PWR_2A_16  POWER  = P0V9_CPU0_RT3_2A
  EG22  GND102  POWER  = GND
  EG32  GND103  POWER  = GND
  EH2  GND105  POWER  = GND
  EH34  GND106  POWER  = GND
  EJ1  GND107  POWER  = GND
  EJ35  GND108  POWER  = GND
  EK7  B_PETP14  OUT  = P5E_CPU0_P3_TX_BUF_DP<1>
  EK26  A_PETP14  OUT  = P5E_CPU0_P3_RX_DP<1>
  EL2  A_PERN14  IN  = P5E_CPU0_P3_RX_BUF_DN<1>
  EL34  B_PERP14  IN  = P5E_CPU0_P3_TX_C_DP<1>
  EM10  B_PETN14  OUT  = P5E_CPU0_P3_TX_BUF_DN<1>
  EM29  A_PETN14  OUT  = P5E_CPU0_P3_RX_DN<1>
  EN1  A_PERP14  IN  = P5E_CPU0_P3_RX_BUF_DP<1>
  EN35  B_PERN14  IN  = P5E_CPU0_P3_TX_C_DN<1>
  EP4  GND112  POWER  = GND
  EP13  GND109  POWER  = GND
  EP17  PWR_2A_17  POWER  = P0V9_CPU0_RT3_2A
  EP20  PWR_2A_18  POWER  = P0V9_CPU0_RT3_2A
  EP22  GND110  POWER  = GND
  EP32  GND111  POWER  = GND
  ER2  GND113  POWER  = GND
  ER34  GND114  POWER  = GND
  ET1  GND115  POWER  = GND
  ET35  GND116  POWER  = GND
  EU7  B_PETP15  OUT  = P5E_CPU0_P3_TX_BUF_DP<0>
  EU26  A_PETP15  OUT  = P5E_CPU0_P3_RX_DP<0>
  EV2  A_PERN15  IN  = P5E_CPU0_P3_RX_BUF_DN<0>
  EV34  B_PERP15  IN  = P5E_CPU0_P3_TX_C_DN<0>
  EW10  B_PETN15  OUT  = P5E_CPU0_P3_TX_BUF_DN<0>
  EW29  A_PETN15  OUT  = P5E_CPU0_P3_RX_DN<0>
  EY1  A_PERP15  IN  = P5E_CPU0_P3_RX_BUF_DP<0>
  EY35  B_PERN15  IN  = P5E_CPU0_P3_TX_C_DP<0>
  F2  PERST_N  IN  = RST_RT_CPU0_P3_PERST_N
  F34  SMB_ADDR1  IN  = RT_CPU0_P3_ADDR1
  FA15  GND117  POWER  = GND
  FA32  GND118  POWER  = GND
  FB2  GND119  POWER  = GND
  FB34  GND120  POWER  = GND
  FC3  GND125  POWER  = GND
  FC6  GND126  POWER  = GND
  FC9  GND127  POWER  = GND
  FC19  GND121  POWER  = GND
  FC23  GND122  POWER  = GND
  FC25  GND123  POWER  = GND
  FC28  GND124  POWER  = GND
  FD1  GND128  POWER  = GND
  FD35  GND129  POWER  = GND
  FE2  NCF_GND7  POWER  = NCF_CPU0_P3_GND
  FE34  NCF_GND8  POWER  = NCF_CPU0_P3_GND
  FF5  EE_CLK  BI  = SMB_RT_CPU0_P3_ROM_MUX_1D_R_SCL
  FF8  JTAG_TEST_MODE  IN  = JTAG_TEST_MODE_RT_CPU0_P3
  FF11  RESET_N  IN  = RST_RT_CPU0_P3_RESET_N
  FF14  GND130  POWER  = GND
  FF18  REFCLKN  IN  = CLK_100M_RETIMER_CPU0_P3_DN
  FF21  GND131  POWER  = GND
  FF24  TEST0  BI  = TEST0_RT_CPU0_P3
  FF27  TEST1  BI  = TEST1_RT_CPU0_P3
  FF30  TEST2  BI  = TEST2_RT_CPU0_P3
  FF33  SCAN_MODE  IN  = RT_CPU0_P3_SCAN_MODE
  FG1  NCF_GND9  POWER  = NCF_CPU0_P3_GND
  FG35  NCF_GND10  POWER  = NCF_CPU0_P3_GND
  FH2  NCF_GND11  POWER  = NCF_CPU0_P3_GND
  FH34  NCF_GND12  POWER  = NCF_CPU0_P3_GND
  FJ3  EE_DAT  BI  = SMB_RT_CPU0_P3_ROM_MUX_1D_R_SDA
  FJ6  GPIO0  BI  = NC
  FJ9  MODE  IN  = MODE_RT_CPU0_P3
  FJ12  GND132  POWER  = GND
  FJ16  REFCLKP  IN  = CLK_100M_RETIMER_CPU0_P3_DP
  FJ19  GND133  POWER  = GND
  FJ23  GPIO1  BI  = NC
  FJ25  GPIO2  BI  = GPIO2_RT_CPU0_P3
  FJ28  GPIO3  BI  = GPIO3_RT_CPU0_P3
  FJ31  INT_N  OUT  = NC
  G1  VQPS  IN  = RT_CPU0_P3_VQPS
  G35  CLKREQ_N  IN  = CLKREQ_RT_CPU0_P3_N
  H12  GND134  POWER  = GND
  H16  GND135  POWER  = GND
  H19  GND136  POWER  = GND
  H31  GND137  POWER  = GND
  J4  GND139  POWER  = GND
  J22  GND138  POWER  = GND
  K2  GND140  POWER  = GND
  K34  GND141  POWER  = GND
  L1  GND142  POWER  = GND
  L35  GND143  POWER  = GND
  M7  B_PETP0  OUT  = P5E_CPU0_P3_TX_BUF_DP<15>
  M26  A_PETP0  OUT  = P5E_CPU0_P3_RX_DP<15>
  N2  A_PERN0  IN  = P5E_CPU0_P3_RX_BUF_DN<15>
  N34  B_PERP0  IN  = P5E_CPU0_P3_TX_C_DN<15>
  P10  B_PETN0  OUT  = P5E_CPU0_P3_TX_BUF_DN<15>
  P29  A_PETN0  OUT  = P5E_CPU0_P3_RX_DN<15>
  R1  A_PERP0  IN  = P5E_CPU0_P3_RX_BUF_DP<15>
  R35  B_PERN0  IN  = P5E_CPU0_P3_TX_C_DP<15>
  T4  GND147  POWER  = GND
  T13  GND144  POWER  = GND
  T17  PWR_2A_19  POWER  = P0V9_CPU0_RT3_2A
  T20  PWR_2A_20  POWER  = P0V9_CPU0_RT3_2A
  T22  GND145  POWER  = GND
  T32  GND146  POWER  = GND
  U2  GND148  POWER  = GND
  U34  GND149  POWER  = GND
  V1  GND150  POWER  = GND
  V35  GND151  POWER  = GND
  W7  B_PETP1  OUT  = P5E_CPU0_P3_TX_BUF_DP<14>
  W26  A_PETP1  OUT  = P5E_CPU0_P3_RX_DP<14>
  Y2  A_PERN1  IN  = P5E_CPU0_P3_RX_BUF_DN<14>
  Y34  B_PERP1  IN  = P5E_CPU0_P3_TX_C_DP<14>
